# T6G (Grand Teton) — schematic netlist excerpt (pin names and nets, part order shuffled) for the footprints in the layout excerpt that follows; sources: Cadence DE-HDL packaged netlist, KiCad conversion of 04192023_DAF0TMB3IC0_F0TG_MB_C_brd_V02_OCP.brd

C257  Q_CAP  1UF 4V 20% X6S  pkg 0201  page 323 : A = P0V9_CPU1_RT0_2A ; B = GND
R2811  Q_RES  33.2 1% CHIP  pkg 0402LF  page 240 : A = SMB_FAN_3V3AUX_BUF_SCL ; B = SMB_FAN_3V3AUX_BUF_R_SCL
R4128  Q_RES  100K 1% CHIP  pkg 0402LF  page 125 : A = P3V3_AUX ; B = GPU_3V3IO_RSVD0_FFU_ISO

(kicad_pcb
	(version 20260206)
	(generator "pcbnew")
	(generator_version "10.0")
	(general
		(thickness 1.6)
		(legacy_teardrops no)
	)
	(paper "A4")
	(title_block
		(title "04192023_DAF0TMB3IC0_F0TG_MB_C_brd_V02_OCP.brd")
		(comment 1 "Grand Teton / footprints 8099-8101 of 8354")
	)
	(layers
		(0 "F.Cu" signal "TOP")
		(4 "In1.Cu" signal "GND")
		(6 "In2.Cu" signal "IN1")
		(8 "In3.Cu" signal "GND1")
		(10 "In4.Cu" signal "IN2")
		(12 "In5.Cu" signal "GND2")
		(14 "In6.Cu" signal "IN3")
		(16 "In7.Cu" signal "GND3")
		(18 "In8.Cu" signal "VCC")
		(20 "In9.Cu" signal "VCC1")
		(22 "In10.Cu" signal "GND4")
		(24 "In11.Cu" signal "IN4")
		(26 "In12.Cu" signal "GND5")
		(28 "In13.Cu" signal "IN5")
		(30 "In14.Cu" signal "GND6")
		(32 "In15.Cu" signal "IN6")
		(34 "In16.Cu" signal "GND7")
		(2 "B.Cu" signal "BOTTOM")
		(9 "F.Adhes" user "F.Adhesive")
		(11 "B.Adhes" user "B.Adhesive")
		(13 "F.Paste" user "Package Geometry/Pastemask Top")
		(15 "B.Paste" user "Package Geometry/Pastemask Bottom")
		(5 "F.SilkS" user "Ref Des/Silkscreen Top")
		(7 "B.SilkS" user "Ref Des/Silkscreen Bottom")
		(1 "F.Mask" user "Board Geometry/Soldermask Top")
		(3 "B.Mask" user "Board Geometry/Soldermask Bottom")
		(17 "Dwgs.User" user "User.Drawings")
		(19 "Cmts.User" user "User.Comments")
		(21 "Eco1.User" user "User.Eco1")
		(23 "Eco2.User" user "User.Eco2")
		(25 "Edge.Cuts" user "Board Geometry/Outline")
		(27 "Margin" user)
		(31 "F.CrtYd" user "Package Geometry/Place Bound Top")
		(29 "B.CrtYd" user "Package Geometry/Place Bound Bottom")
		(35 "F.Fab" user "Ref Des/Assembly Top")
		(33 "B.Fab" user "Ref Des/Assembly Bottom")
	)
	(footprint ""
		(layer "B.Cu")
		(at 45.418502 -387.05028)
		(property "Reference" "C257"
			(at 0 0 0)
			(layer "B.SilkS")
			(hide yes)
			(effects
				(font
					(size 1.27 1.27)
				)
				(justify mirror)
			)
		)
		(property "Value" ""
			(at 0 0 0)
			(layer "B.Fab")
			(effects
				(font
					(size 1.27 1.27)
				)
				(justify mirror)
			)
		)
		(duplicate_pad_numbers_are_jumpers no)
		(fp_line
			(start -0.299974 -0.150114)
			(end -0.299974 0.150114)
			(stroke
				(width 0.1)
				(type default)
			)
			(layer "B.Fab")
		)
		(fp_line
			(start -0.299974 0.150114)
			(end 0.299974 0.150114)
			(stroke
				(width 0.1)
				(type default)
			)
			(layer "B.Fab")
		)
		(fp_line
			(start 0.299974 -0.150114)
			(end -0.299974 -0.150114)
			(stroke
				(width 0.1)
				(type default)
			)
			(layer "B.Fab")
		)
		(fp_line
			(start 0.299974 0.150114)
			(end 0.299974 -0.150114)
			(stroke
				(width 0.1)
				(type default)
			)
			(layer "B.Fab")
		)
		(pad "1" smd rect
			(at 0.2667 0 180)
			(size 0.3048 0.381)
			(layers "B.Cu" "B.Mask" "B.Paste")
			(net "P0V9_CPU1_RT0_2A")
		)
		(pad "2" smd rect
			(at -0.2667 0 180)
			(size 0.3048 0.381)
			(layers "B.Cu" "B.Mask" "B.Paste")
			(net "GND")
		)
	)
	(footprint ""
		(layer "B.Cu")
		(at 167.377618 -417.962588)
		(property "Reference" "R4128"
			(at 0 0 0)
			(layer "B.SilkS")
			(hide yes)
			(effects
				(font
					(size 1.27 1.27)
				)
				(justify mirror)
			)
		)
		(property "Value" ""
			(at 0 0 0)
			(layer "B.Fab")
			(effects
				(font
					(size 1.27 1.27)
				)
				(justify mirror)
			)
		)
		(duplicate_pad_numbers_are_jumpers no)
		(fp_line
			(start -0.7874 -0.4064)
			(end -0.7874 0.4064)
			(stroke
				(width 0.1524)
				(type default)
			)
			(layer "B.SilkS")
		)
		(fp_line
			(start -0.7874 0.4064)
			(end 0.7874 0.4064)
			(stroke
				(width 0.1524)
				(type default)
			)
			(layer "B.SilkS")
		)
		(fp_line
			(start 0.7874 -0.4064)
			(end -0.7874 -0.4064)
			(stroke
				(width 0.1524)
				(type default)
			)
			(layer "B.SilkS")
		)
		(fp_line
			(start 0.7874 0.4064)
			(end 0.7874 -0.4064)
			(stroke
				(width 0.1524)
				(type default)
			)
			(layer "B.SilkS")
		)
		(fp_line
			(start -0.67945 -0.3048)
			(end -0.67945 0.3048)
			(stroke
				(width 0.1)
				(type default)
			)
			(layer "B.Fab")
		)
		(fp_line
			(start -0.67945 0.3048)
			(end -0.120396 0.3048)
			(stroke
				(width 0.1)
				(type default)
			)
			(layer "B.Fab")
		)
		(fp_line
			(start -0.12065 -0.3048)
			(end -0.67945 -0.3048)
			(stroke
				(width 0.1)
				(type default)
			)
			(layer "B.Fab")
		)
		(fp_line
			(start -0.12065 -0.2794)
			(end -0.12065 -0.3048)
			(stroke
				(width 0.1)
				(type default)
			)
			(layer "B.Fab")
		)
		(fp_line
			(start -0.120396 0.2794)
			(end 0.12065 0.2794)
			(stroke
				(width 0.1)
				(type default)
			)
			(layer "B.Fab")
		)
		(fp_line
			(start -0.120396 0.3048)
			(end -0.120396 0.2794)
			(stroke
				(width 0.1)
				(type default)
			)
			(layer "B.Fab")
		)
		(fp_line
			(start 0.12065 -0.305054)
			(end 0.12065 -0.2794)
			(stroke
				(width 0.1)
				(type default)
			)
			(layer "B.Fab")
		)
		(fp_line
			(start 0.12065 -0.2794)
			(end -0.12065 -0.2794)
			(stroke
				(width 0.1)
				(type default)
			)
			(layer "B.Fab")
		)
		(fp_line
			(start 0.12065 0.2794)
			(end 0.12065 0.3048)
			(stroke
				(width 0.1)
				(type default)
			)
			(layer "B.Fab")
		)
		(fp_line
			(start 0.12065 0.3048)
			(end 0.67945 0.3048)
			(stroke
				(width 0.1)
				(type default)
			)
			(layer "B.Fab")
		)
		(fp_line
			(start 0.67945 -0.305054)
			(end 0.12065 -0.305054)
			(stroke
				(width 0.1)
				(type default)
			)
			(layer "B.Fab")
		)
		(fp_line
			(start 0.67945 0.3048)
			(end 0.67945 -0.305054)
			(stroke
				(width 0.1)
				(type default)
			)
			(layer "B.Fab")
		)
		(pad "1" smd circle
			(at 0.40005 0 180)
			(size 0 0)
			(layers "B.Cu" "B.Mask" "B.Paste")
			(net "P3V3_AUX")
		)
		(pad "2" smd circle
			(at -0.40005 0 180)
			(size 0 0)
			(layers "B.Cu" "B.Mask" "B.Paste")
			(net "GPU_3V3IO_RSVD0_FFU_ISO")
		)
	)
	(footprint ""
		(layer "B.Cu")
		(at 184.681114 -417.575238 180)
		(property "Reference" "R2811"
			(at 0 0 0)
			(layer "B.SilkS")
			(hide yes)
			(effects
				(font
					(size 1.27 1.27)
				)
				(justify mirror)
			)
		)
		(property "Value" ""
			(at 0 0 0)
			(layer "B.Fab")
			(effects
				(font
					(size 1.27 1.27)
				)
				(justify mirror)
			)
		)
		(duplicate_pad_numbers_are_jumpers no)
		(fp_line
			(start 0.7874 0.4064)
			(end 0.7874 -0.4064)
			(stroke
				(width 0.1524)
				(type default)
			)
			(layer "B.SilkS")
		)
		(fp_line
			(start 0.7874 -0.4064)
			(end -0.7874 -0.4064)
			(stroke
				(width 0.1524)
				(type default)
			)
			(layer "B.SilkS")
		)
		(fp_line
			(start -0.7874 0.4064)
			(end 0.7874 0.4064)
			(stroke
				(width 0.1524)
				(type default)
			)
			(layer "B.SilkS")
		)
		(fp_line
			(start -0.7874 -0.4064)
			(end -0.7874 0.4064)
			(stroke
				(width 0.1524)
				(type default)
			)
			(layer "B.SilkS")
		)
		(fp_line
			(start 0.67945 0.3048)
			(end 0.67945 -0.305054)
			(stroke
				(width 0.1)
				(type default)
			)
			(layer "B.Fab")
		)
		(fp_line
			(start 0.67945 -0.305054)
			(end 0.12065 -0.305054)
			(stroke
				(width 0.1)
				(type default)
			)
			(layer "B.Fab")
		)
		(fp_line
			(start 0.12065 0.3048)
			(end 0.67945 0.3048)
			(stroke
				(width 0.1)
				(type default)
			)
			(layer "B.Fab")
		)
		(fp_line
			(start 0.12065 0.2794)
			(end 0.12065 0.3048)
			(stroke
				(width 0.1)
				(type default)
			)
			(layer "B.Fab")
		)
		(fp_line
			(start 0.12065 -0.2794)
			(end -0.12065 -0.2794)
			(stroke
				(width 0.1)
				(type default)
			)
			(layer "B.Fab")
		)
		(fp_line
			(start 0.12065 -0.305054)
			(end 0.12065 -0.2794)
			(stroke
				(width 0.1)
				(type default)
			)
			(layer "B.Fab")
		)
		(fp_line
			(start -0.120396 0.3048)
			(end -0.120396 0.2794)
			(stroke
				(width 0.1)
				(type default)
			)
			(layer "B.Fab")
		)
		(fp_line
			(start -0.120396 0.2794)
			(end 0.12065 0.2794)
			(stroke
				(width 0.1)
				(type default)
			)
			(layer "B.Fab")
		)
		(fp_line
			(start -0.12065 -0.2794)
			(end -0.12065 -0.3048)
			(stroke
				(width 0.1)
				(type default)
			)
			(layer "B.Fab")
		)
		(fp_line
			(start -0.12065 -0.3048)
			(end -0.67945 -0.3048)
			(stroke
				(width 0.1)
				(type default)
			)
			(layer "B.Fab")
		)
		(fp_line
			(start -0.67945 0.3048)
			(end -0.120396 0.3048)
			(stroke
				(width 0.1)
				(type default)
			)
			(layer "B.Fab")
		)
		(fp_line
			(start -0.67945 -0.3048)
			(end -0.67945 0.3048)
			(stroke
				(width 0.1)
				(type default)
			)
			(layer "B.Fab")
		)
		(pad "1" smd circle
			(at 0.40005 0)
			(size 0 0)
			(layers "B.Cu" "B.Mask" "B.Paste")
			(net "SMB_FAN_3V3AUX_BUF_SCL")
		)
		(pad "2" smd circle
			(at -0.40005 0)
			(size 0 0)
			(layers "B.Cu" "B.Mask" "B.Paste")
			(net "SMB_FAN_3V3AUX_BUF_R_SCL")
		)
	)
)
